(kicad_pcb
	(version 20260206)
	(generator "pcbnew")
	(generator_version "10.0")
	(general
		(thickness 1.6)
		(legacy_teardrops no)
	)
	(paper "A4")
	(title_block
		(title "fcb — Lightning_FCB_BRD.brd")
		(comment 1 "Lightning (Wiwynn / Facebook NVMe JBOF) / footprints 455-461 of 495")
	)
	(layers
		(0 "F.Cu" signal "TOP")
		(4 "In1.Cu" signal "L2GND")
		(6 "In2.Cu" signal "L3VCC")
		(2 "B.Cu" signal "BOTTOM")
		(9 "F.Adhes" user "F.Adhesive")
		(11 "B.Adhes" user "B.Adhesive")
		(13 "F.Paste" user "Package Geometry/Pastemask Top")
		(15 "B.Paste" user "Package Geometry/Pastemask Bottom")
		(5 "F.SilkS" user "Ref Des/Silkscreen Top")
		(7 "B.SilkS" user "Ref Des/Silkscreen Bottom")
		(1 "F.Mask" user "Board Geometry/Soldermask Top")
		(3 "B.Mask" user "Board Geometry/Soldermask Bottom")
		(17 "Dwgs.User" user "User.Drawings")
		(19 "Cmts.User" user "User.Comments")
		(21 "Eco1.User" user "User.Eco1")
		(23 "Eco2.User" user "User.Eco2")
		(25 "Edge.Cuts" user "Board Geometry/Outline")
		(27 "Margin" user)
		(31 "F.CrtYd" user "Package Geometry/Place Bound Top")
		(29 "B.CrtYd" user "Package Geometry/Place Bound Bottom")
		(35 "F.Fab" user "Ref Des/Assembly Top")
		(33 "B.Fab" user "Ref Des/Assembly Bottom")
	)
	(footprint ""
		(layer "F.Cu")
		(at 35.0266 -378.3076 180)
		(property "Reference" "PR51"
			(at 0 0 180)
			(layer "F.SilkS")
			(hide yes)
			(effects
				(font
					(size 1.27 1.27)
				)
			)
		)
		(property "Value" "10R2F-L-GP"
			(at 0.064008 -3.993896 180)
			(unlocked yes)
			(layer "F.Fab")
			(hide yes)
			(effects
				(font
					(size 1.016 1.016)
					(thickness 0.1524)
				)
			)
		)
		(property "Device Type" "R402H14"
			(at 0.064008 -5.517896 180)
			(unlocked yes)
			(layer "F.Fab")
			(hide yes)
			(effects
				(font
					(size 1.016 1.016)
					(thickness 0.1524)
				)
			)
		)
		(duplicate_pad_numbers_are_jumpers no)
		(fp_line
			(start 0.508 -0.9398)
			(end -0.508 -0.9398)
			(stroke
				(width 0.1524)
				(type default)
			)
			(layer "F.SilkS")
		)
		(fp_line
			(start -0.508 -0.9398)
			(end -0.508 0.9398)
			(stroke
				(width 0.1524)
				(type default)
			)
			(layer "F.SilkS")
		)
		(fp_rect
			(start -0.508 0.9398)
			(end 0.508 -0.9398)
			(stroke
				(width 0)
				(type default)
			)
			(fill no)
			(layer "F.CrtYd")
		)
		(fp_rect
			(start -0.508 0.9398)
			(end 0.508 -0.9398)
			(stroke
				(width 0)
				(type default)
			)
			(fill no)
			(layer "F.Fab")
		)
		(pad "1" smd custom
			(at 0 -0.4445 180)
			(size 0.1397 0.1397)
			(layers "F.Cu" "F.Mask" "F.Paste")
			(net "ADM1276_GATE")
			(options
				(clearance outline)
				(anchor circle)
			)
			(primitives
				(gr_poly
					(pts
						(arc
							(start -0.1778 -0.2794)
							(mid -0.249642 -0.249642)
							(end -0.2794 -0.1778)
						)
						(arc
							(start -0.2794 0.1778)
							(mid -0.249642 0.249642)
							(end -0.1778 0.2794)
						)
						(arc
							(start 0.1778 0.2794)
							(mid 0.249642 0.249642)
							(end 0.2794 0.1778)
						)
						(arc
							(start 0.2794 -0.1778)
							(mid 0.249642 -0.249642)
							(end 0.1778 -0.2794)
						)
					)
					(width 0)
					(fill yes)
				)
			)
		)
		(pad "2" smd custom
			(at 0 0.4445 180)
			(size 0.1397 0.1397)
			(layers "F.Cu" "F.Mask" "F.Paste")
			(net "ADM1276_GATE_DRV0")
			(options
				(clearance outline)
				(anchor circle)
			)
			(primitives
				(gr_poly
					(pts
						(arc
							(start -0.1778 -0.2794)
							(mid -0.249642 -0.249642)
							(end -0.2794 -0.1778)
						)
						(arc
							(start -0.2794 0.1778)
							(mid -0.249642 0.249642)
							(end -0.1778 0.2794)
						)
						(arc
							(start 0.1778 0.2794)
							(mid 0.249642 0.249642)
							(end 0.2794 0.1778)
						)
						(arc
							(start 0.2794 -0.1778)
							(mid 0.249642 -0.249642)
							(end 0.1778 -0.2794)
						)
					)
					(width 0)
					(fill yes)
				)
			)
		)
	)
	(footprint ""
		(layer "F.Cu")
		(at 39.243 -178.054 180)
		(property "Reference" "PR45"
			(at 0 0 180)
			(layer "F.SilkS")
			(hide yes)
			(effects
				(font
					(size 1.27 1.27)
				)
			)
		)
		(property "Value" "10KR2F-2-GP"
			(at 0.064008 -3.993896 180)
			(unlocked yes)
			(layer "F.Fab")
			(hide yes)
			(effects
				(font
					(size 1.016 1.016)
					(thickness 0.1524)
				)
			)
		)
		(property "Device Type" "R402H16"
			(at 0.064008 -5.517896 180)
			(unlocked yes)
			(layer "F.Fab")
			(hide yes)
			(effects
				(font
					(size 1.016 1.016)
					(thickness 0.1524)
				)
			)
		)
		(duplicate_pad_numbers_are_jumpers no)
		(fp_line
			(start 0.508 -0.9398)
			(end -0.508 -0.9398)
			(stroke
				(width 0.1524)
				(type default)
			)
			(layer "F.SilkS")
		)
		(fp_line
			(start -0.508 -0.9398)
			(end -0.508 0.9398)
			(stroke
				(width 0.1524)
				(type default)
			)
			(layer "F.SilkS")
		)
		(fp_rect
			(start -0.508 0.9398)
			(end 0.508 -0.9398)
			(stroke
				(width 0)
				(type default)
			)
			(fill no)
			(layer "F.CrtYd")
		)
		(fp_rect
			(start -0.508 0.9398)
			(end 0.508 -0.9398)
			(stroke
				(width 0)
				(type default)
			)
			(fill no)
			(layer "F.Fab")
		)
		(pad "1" smd custom
			(at 0 -0.4445 180)
			(size 0.1397 0.1397)
			(layers "F.Cu" "F.Mask" "F.Paste")
			(net "P3V3_AUX")
			(options
				(clearance outline)
				(anchor circle)
			)
			(primitives
				(gr_poly
					(pts
						(arc
							(start -0.1778 -0.2794)
							(mid -0.249642 -0.249642)
							(end -0.2794 -0.1778)
						)
						(arc
							(start -0.2794 0.1778)
							(mid -0.249642 0.249642)
							(end -0.1778 0.2794)
						)
						(arc
							(start 0.1778 0.2794)
							(mid 0.249642 0.249642)
							(end 0.2794 0.1778)
						)
						(arc
							(start 0.2794 -0.1778)
							(mid 0.249642 -0.249642)
							(end 0.1778 -0.2794)
						)
					)
					(width 0)
					(fill yes)
				)
			)
		)
		(pad "2" smd custom
			(at 0 0.4445 180)
			(size 0.1397 0.1397)
			(layers "F.Cu" "F.Mask" "F.Paste")
			(net "TEMP_ALM#_IN_D")
			(options
				(clearance outline)
				(anchor circle)
			)
			(primitives
				(gr_poly
					(pts
						(arc
							(start -0.1778 -0.2794)
							(mid -0.249642 -0.249642)
							(end -0.2794 -0.1778)
						)
						(arc
							(start -0.2794 0.1778)
							(mid -0.249642 0.249642)
							(end -0.1778 0.2794)
						)
						(arc
							(start 0.1778 0.2794)
							(mid 0.249642 0.249642)
							(end 0.2794 0.1778)
						)
						(arc
							(start 0.2794 -0.1778)
							(mid 0.249642 -0.249642)
							(end 0.1778 -0.2794)
						)
					)
					(width 0)
					(fill yes)
				)
			)
		)
	)
	(footprint ""
		(layer "F.Cu")
		(at 43.2054 -155.2956 180)
		(property "Reference" "C3"
			(at 0 0 180)
			(layer "F.SilkS")
			(hide yes)
			(effects
				(font
					(size 1.27 1.27)
				)
			)
		)
		(property "Value" "SC10U25V5KX-GP"
			(at -0.0762 -6.1214 180)
			(unlocked yes)
			(layer "F.Fab")
			(hide yes)
			(effects
				(font
					(size 1.016 1.016)
					(thickness 0.1524)
				)
			)
		)
		(property "Device Type" "C805H56"
			(at -0.0762 -8.1534 180)
			(unlocked yes)
			(layer "F.Fab")
			(hide yes)
			(effects
				(font
					(size 1.016 1.016)
					(thickness 0.1524)
				)
			)
		)
		(duplicate_pad_numbers_are_jumpers no)
		(fp_line
			(start 0.635 0)
			(end -0.635 0)
			(stroke
				(width 0.508)
				(type default)
			)
			(layer "F.SilkS")
		)
		(fp_rect
			(start -0.9652 1.778)
			(end 0.9652 -1.778)
			(stroke
				(width 0)
				(type default)
			)
			(fill no)
			(layer "F.CrtYd")
		)
		(fp_poly
			(pts
				(xy -0.9652 -1.778) (xy 0.9652 -1.778) (xy 0.9652 1.778) (xy -0.9652 1.778)
			)
			(stroke
				(width 0)
				(type default)
			)
			(fill no)
			(layer "F.Fab")
		)
		(pad "1" smd rect
			(at 0 -0.9652 180)
			(size 1.397 1.143)
			(layers "F.Cu" "F.Mask" "F.Paste")
			(net "NCT7904_3VSB")
		)
		(pad "2" smd rect
			(at 0 0.9652 180)
			(size 1.397 1.143)
			(layers "F.Cu" "F.Mask" "F.Paste")
			(net "GND")
		)
	)
	(footprint ""
		(layer "F.Cu")
		(at 23.4442 -222.416116 180)
		(property "Reference" "C15"
			(at 0 0 180)
			(layer "F.SilkS")
			(hide yes)
			(effects
				(font
					(size 1.27 1.27)
				)
			)
		)
		(property "Value" "SC1U16V3KX-5GP"
			(at 0 -2.8194 180)
			(unlocked yes)
			(layer "F.Fab")
			(hide yes)
			(effects
				(font
					(size 1.016 1.016)
					(thickness 0.1524)
				)
			)
		)
		(property "Device Type" "C603H36"
			(at 0 -4.3434 180)
			(unlocked yes)
			(layer "F.Fab")
			(hide yes)
			(effects
				(font
					(size 1.016 1.016)
					(thickness 0.1524)
				)
			)
		)
		(duplicate_pad_numbers_are_jumpers no)
		(fp_line
			(start 0.508 0)
			(end -0.508 0)
			(stroke
				(width 0.2032)
				(type default)
			)
			(layer "F.SilkS")
		)
		(fp_rect
			(start -0.5842 1.3335)
			(end 0.5842 -1.3335)
			(stroke
				(width 0)
				(type default)
			)
			(fill no)
			(layer "F.CrtYd")
		)
		(fp_rect
			(start -0.5842 1.3335)
			(end 0.5842 -1.3335)
			(stroke
				(width 0)
				(type default)
			)
			(fill no)
			(layer "F.Fab")
		)
		(pad "1" smd custom
			(at 0 -0.762 180)
			(size 0.2159 0.2159)
			(layers "F.Cu" "F.Mask" "F.Paste")
			(net "P3V3")
			(options
				(clearance outline)
				(anchor circle)
			)
			(primitives
				(gr_poly
					(pts
						(arc
							(start -0.3302 -0.4318)
							(mid -0.402042 -0.402042)
							(end -0.4318 -0.3302)
						)
						(arc
							(start -0.4318 0.3302)
							(mid -0.402042 0.402042)
							(end -0.3302 0.4318)
						)
						(arc
							(start 0.3302 0.4318)
							(mid 0.402042 0.402042)
							(end 0.4318 0.3302)
						)
						(arc
							(start 0.4318 -0.3302)
							(mid 0.402042 -0.402042)
							(end 0.3302 -0.4318)
						)
					)
					(width 0)
					(fill yes)
				)
			)
		)
		(pad "2" smd custom
			(at 0 0.762 180)
			(size 0.2159 0.2159)
			(layers "F.Cu" "F.Mask" "F.Paste")
			(net "GND")
			(options
				(clearance outline)
				(anchor circle)
			)
			(primitives
				(gr_poly
					(pts
						(arc
							(start -0.3302 -0.4318)
							(mid -0.402042 -0.402042)
							(end -0.4318 -0.3302)
						)
						(arc
							(start -0.4318 0.3302)
							(mid -0.402042 0.402042)
							(end -0.3302 0.4318)
						)
						(arc
							(start 0.3302 0.4318)
							(mid 0.402042 0.402042)
							(end 0.4318 0.3302)
						)
						(arc
							(start 0.4318 -0.3302)
							(mid 0.402042 -0.402042)
							(end 0.3302 -0.4318)
						)
					)
					(width 0)
					(fill yes)
				)
			)
		)
	)
	(footprint ""
		(layer "F.Cu")
		(at 43.9166 -101.0666 90)
		(property "Reference" "TC8"
			(at 0 0 90)
			(layer "F.SilkS")
			(hide yes)
			(effects
				(font
					(size 1.27 1.27)
				)
			)
		)
		(property "Value" "ST15U25VDM-1-GP"
			(at 0 -9.6012 90)
			(unlocked yes)
			(layer "F.Fab")
			(hide yes)
			(effects
				(font
					(size 1.016 1.016)
					(thickness 0.1524)
				)
			)
		)
		(property "Device Type" "CT7343H79"
			(at 0 -11.1252 90)
			(unlocked yes)
			(layer "F.Fab")
			(hide yes)
			(effects
				(font
					(size 1.016 1.016)
					(thickness 0.1524)
				)
			)
		)
		(duplicate_pad_numbers_are_jumpers no)
		(fp_line
			(start 2.286 -4.8768)
			(end -2.286 -4.8768)
			(stroke
				(width 0.1524)
				(type default)
			)
			(layer "F.SilkS")
		)
		(fp_line
			(start -2.286 -4.8768)
			(end -2.286 -2.032)
			(stroke
				(width 0.1524)
				(type default)
			)
			(layer "F.SilkS")
		)
		(fp_line
			(start 2.1082 -4.699)
			(end -2.1082 -4.699)
			(stroke
				(width 0.508)
				(type default)
			)
			(layer "F.SilkS")
		)
		(fp_line
			(start 2.286 -2.032)
			(end 2.286 -4.8768)
			(stroke
				(width 0.1524)
				(type default)
			)
			(layer "F.SilkS")
		)
		(fp_line
			(start 2.286 2.032)
			(end 2.286 4.8768)
			(stroke
				(width 0.1524)
				(type default)
			)
			(layer "F.SilkS")
		)
		(fp_line
			(start 2.286 4.8768)
			(end -2.286 4.8768)
			(stroke
				(width 0.1524)
				(type default)
			)
			(layer "F.SilkS")
		)
		(fp_line
			(start -2.286 4.8768)
			(end -2.286 2.032)
			(stroke
				(width 0.1524)
				(type default)
			)
			(layer "F.SilkS")
		)
		(fp_rect
			(start -2.1463 3.6449)
			(end 2.1463 -3.6449)
			(stroke
				(width 0)
				(type default)
			)
			(fill no)
			(layer "F.CrtYd")
		)
		(fp_poly
			(pts
				(xy -2.54 4.953) (xy -2.54 4.2926) (xy -3.81 4.2926) (xy -3.81 -4.2926) (xy -2.54 -4.2926) (xy -2.54 -4.953)
				(xy 2.54 -4.953) (xy 2.54 -4.2926) (xy 3.81 -4.2926) (xy 3.81 -1.6256) (xy 2.1463 -1.6256) (xy 2.1463 -3.6449)
				(xy -2.1463 -3.6449) (xy -2.1463 3.6449) (xy 2.1463 3.6449) (xy 2.1463 -1.6129) (xy 3.81 -1.6129)
				(xy 3.81 4.2926) (xy 2.54 4.2926) (xy 2.54 4.953)
			)
			(stroke
				(width 0)
				(type default)
			)
			(fill no)
			(layer "F.CrtYd")
		)
		(fp_rect
			(start 2.54 4.2926)
			(end 3.81 -4.2926)
			(stroke
				(width 0)
				(type default)
			)
			(fill no)
			(layer "F.Fab")
		)
		(fp_rect
			(start -3.81 4.2926)
			(end -2.54 -4.2926)
			(stroke
				(width 0)
				(type default)
			)
			(fill no)
			(layer "F.Fab")
		)
		(fp_rect
			(start -2.54 4.953)
			(end 2.54 -4.953)
			(stroke
				(width 0)
				(type default)
			)
			(fill no)
			(layer "F.Fab")
		)
		(pad "1" smd rect
			(at 0 -3.1496 90)
			(size 2.413 2.286)
			(layers "F.Cu" "F.Mask" "F.Paste")
			(net "P12VL")
		)
		(pad "2" smd rect
			(at 0 3.1496 90)
			(size 2.413 2.286)
			(layers "F.Cu" "F.Mask" "F.Paste")
			(net "GND")
		)
		(zone
			(layer "F.Cu")
			(hatch none 0.5)
			(connect_pads
				(clearance 0)
			)
			(min_thickness 0.25)
			(keepout
				(tracks allowed)
				(vias not_allowed)
				(pads allowed)
				(copperpour not_allowed)
				(footprints allowed)
			)
			(placement
				(enabled no)
				(sheetname "")
			)
			(fill
				(thermal_gap 0.5)
				(thermal_bridge_width 0.5)
				(island_removal_mode 0)
			)
			(polygon
				(pts
					(xy 42.2275 -102.5779) (xy 39.3192 -102.5779) (xy 39.3192 -99.5553) (xy 42.2148 -99.5553) (xy 42.545 -99.5553)
					(xy 42.545 -102.5779)
				)
			)
		)
		(zone
			(layer "F.Cu")
			(hatch none 0.5)
			(connect_pads
				(clearance 0)
			)
			(min_thickness 0.25)
			(keepout
				(tracks allowed)
				(vias not_allowed)
				(pads allowed)
				(copperpour not_allowed)
				(footprints allowed)
			)
			(placement
				(enabled no)
				(sheetname "")
			)
			(fill
				(thermal_gap 0.5)
				(thermal_bridge_width 0.5)
				(island_removal_mode 0)
			)
			(polygon
				(pts
					(xy 48.514 -99.5553) (xy 48.514 -102.5779) (xy 45.6184 -102.5779) (xy 45.2882 -102.5779) (xy 45.2882 -99.5553)
					(xy 45.6184 -99.5553)
				)
			)
		)
	)
	(footprint ""
		(layer "F.Cu")
		(at 30.3022 -224.3074)
		(property "Reference" "R138"
			(at 0 0 0)
			(layer "F.SilkS")
			(hide yes)
			(effects
				(font
					(size 1.27 1.27)
				)
			)
		)
		(property "Value" "0R2J-2-GP"
			(at 0.064008 -3.993896 0)
			(unlocked yes)
			(layer "F.Fab")
			(hide yes)
			(effects
				(font
					(size 1.016 1.016)
					(thickness 0.1524)
				)
			)
		)
		(property "Device Type" "R402H16"
			(at 0.064008 -5.517896 0)
			(unlocked yes)
			(layer "F.Fab")
			(hide yes)
			(effects
				(font
					(size 1.016 1.016)
					(thickness 0.1524)
				)
			)
		)
		(duplicate_pad_numbers_are_jumpers no)
		(fp_line
			(start -0.508 -0.9398)
			(end -0.508 0.9398)
			(stroke
				(width 0.1524)
				(type default)
			)
			(layer "F.SilkS")
		)
		(fp_line
			(start 0.508 -0.9398)
			(end -0.508 -0.9398)
			(stroke
				(width 0.1524)
				(type default)
			)
			(layer "F.SilkS")
		)
		(fp_rect
			(start -0.508 0.9398)
			(end 0.508 -0.9398)
			(stroke
				(width 0)
				(type default)
			)
			(fill no)
			(layer "F.CrtYd")
		)
		(fp_rect
			(start -0.508 0.9398)
			(end 0.508 -0.9398)
			(stroke
				(width 0)
				(type default)
			)
			(fill no)
			(layer "F.Fab")
		)
		(pad "1" smd custom
			(at 0 -0.4445)
			(size 0.1397 0.1397)
			(layers "F.Cu" "F.Mask" "F.Paste")
			(net "PWM_OUT_FAN3_NET")
			(options
				(clearance outline)
				(anchor circle)
			)
			(primitives
				(gr_poly
					(pts
						(arc
							(start -0.1778 -0.2794)
							(mid -0.249642 -0.249642)
							(end -0.2794 -0.1778)
						)
						(arc
							(start -0.2794 0.1778)
							(mid -0.249642 0.249642)
							(end -0.1778 0.2794)
						)
						(arc
							(start 0.1778 0.2794)
							(mid 0.249642 0.249642)
							(end 0.2794 0.1778)
						)
						(arc
							(start 0.2794 -0.1778)
							(mid 0.249642 -0.249642)
							(end 0.1778 -0.2794)
						)
					)
					(width 0)
					(fill yes)
				)
			)
		)
		(pad "2" smd custom
			(at 0 0.4445)
			(size 0.1397 0.1397)
			(layers "F.Cu" "F.Mask" "F.Paste")
			(net "PWM_OUT_FAN3")
			(options
				(clearance outline)
				(anchor circle)
			)
			(primitives
				(gr_poly
					(pts
						(arc
							(start -0.1778 -0.2794)
							(mid -0.249642 -0.249642)
							(end -0.2794 -0.1778)
						)
						(arc
							(start -0.2794 0.1778)
							(mid -0.249642 0.249642)
							(end -0.1778 0.2794)
						)
						(arc
							(start 0.1778 0.2794)
							(mid 0.249642 0.249642)
							(end 0.2794 0.1778)
						)
						(arc
							(start 0.2794 -0.1778)
							(mid 0.249642 -0.249642)
							(end 0.1778 -0.2794)
						)
					)
					(width 0)
					(fill yes)
				)
			)
		)
	)
	(footprint ""
		(layer "F.Cu")
		(at 9.4488 -74.7522 -90)
		(property "Reference" "C23"
			(at 0 0 270)
			(layer "F.SilkS")
			(hide yes)
			(effects
				(font
					(size 1.27 1.27)
				)
			)
		)
		(property "Value" "SCD1U50V3KX-GP"
			(at 0 -2.8194 270)
			(unlocked yes)
			(layer "F.Fab")
			(hide yes)
			(effects
				(font
					(size 1.016 1.016)
					(thickness 0.1524)
				)
			)
		)
		(property "Device Type" "C603H36"
			(at 0 -4.3434 270)
			(unlocked yes)
			(layer "F.Fab")
			(hide yes)
			(effects
				(font
					(size 1.016 1.016)
					(thickness 0.1524)
				)
			)
		)
		(duplicate_pad_numbers_are_jumpers no)
		(fp_line
			(start 0.508 0)
			(end -0.508 0)
			(stroke
				(width 0.2032)
				(type default)
			)
			(layer "F.SilkS")
		)
		(fp_rect
			(start -0.5842 1.3335)
			(end 0.5842 -1.3335)
			(stroke
				(width 0)
				(type default)
			)
			(fill no)
			(layer "F.CrtYd")
		)
		(fp_rect
			(start -0.5842 1.3335)
			(end 0.5842 -1.3335)
			(stroke
				(width 0)
				(type default)
			)
			(fill no)
			(layer "F.Fab")
		)
		(pad "1" smd custom
			(at 0 -0.762 270)
			(size 0.2159 0.2159)
			(layers "F.Cu" "F.Mask" "F.Paste")
			(net "P12VU")
			(options
				(clearance outline)
				(anchor circle)
			)
			(primitives
				(gr_poly
					(pts
						(arc
							(start -0.3302 -0.4318)
							(mid -0.402042 -0.402042)
							(end -0.4318 -0.3302)
						)
						(arc
							(start -0.4318 0.3302)
							(mid -0.402042 0.402042)
							(end -0.3302 0.4318)
						)
						(arc
							(start 0.3302 0.4318)
							(mid 0.402042 0.402042)
							(end 0.4318 0.3302)
						)
						(arc
							(start 0.4318 -0.3302)
							(mid 0.402042 -0.402042)
							(end 0.3302 -0.4318)
						)
					)
					(width 0)
					(fill yes)
				)
			)
		)
		(pad "2" smd custom
			(at 0 0.762 270)
			(size 0.2159 0.2159)
			(layers "F.Cu" "F.Mask" "F.Paste")
			(net "GND")
			(options
				(clearance outline)
				(anchor circle)
			)
			(primitives
				(gr_poly
					(pts
						(arc
							(start -0.3302 -0.4318)
							(mid -0.402042 -0.402042)
							(end -0.4318 -0.3302)
						)
						(arc
							(start -0.4318 0.3302)
							(mid -0.402042 0.402042)
							(end -0.3302 0.4318)
						)
						(arc
							(start 0.3302 0.4318)
							(mid 0.402042 0.402042)
							(end 0.4318 0.3302)
						)
						(arc
							(start 0.4318 -0.3302)
							(mid 0.402042 -0.402042)
							(end 0.3302 -0.4318)
						)
					)
					(width 0)
					(fill yes)
				)
			)
		)
	)
)
